# S9S_MB_2U (Grand Teton) — schematic netlist excerpt (pin names and nets, part order shuffled) for the footprints in the layout excerpt that follows; sources: Cadence DE-HDL packaged netlist, KiCad conversion of 03242023_DA0F0TMBIJ0_F0T_Motherboard_J_brd_V01_OCP.brd

R2211  Q_RES  0 5% CHIP  pkg 0402LF  page 236 : A = SMB_S3M_CPU1_3V3AUX_SCL_R ; B = SMB_S3M_CPU1_3V3AUX_SCL
C253  Q_CAP  10UF 6.3V 20% X6S  pkg C0402  page 77 : A = PVCCIN_CPU1 ; B = GND

(kicad_pcb
	(version 20260206)
	(generator "pcbnew")
	(generator_version "10.0")
	(general
		(thickness 1.6)
		(legacy_teardrops no)
	)
	(paper "A4")
	(title_block
		(title "03242023_DA0F0TMBIJ0_F0T_Motherboard_J_brd_V01_OCP.brd")
		(comment 1 "Grand Teton / footprints 1210-1211 of 6105")
	)
	(layers
		(0 "F.Cu" signal "TOP")
		(4 "In1.Cu" signal "GND")
		(6 "In2.Cu" signal "IN1")
		(8 "In3.Cu" signal "GND1")
		(10 "In4.Cu" signal "IN2")
		(12 "In5.Cu" signal "GND2")
		(14 "In6.Cu" signal "IN3")
		(16 "In7.Cu" signal "GND3")
		(18 "In8.Cu" signal "VCC")
		(20 "In9.Cu" signal "VCC1")
		(22 "In10.Cu" signal "GND4")
		(24 "In11.Cu" signal "IN4")
		(26 "In12.Cu" signal "GND5")
		(28 "In13.Cu" signal "IN5")
		(30 "In14.Cu" signal "GND6")
		(32 "In15.Cu" signal "IN6")
		(34 "In16.Cu" signal "GND7")
		(2 "B.Cu" signal "BOTTOM")
		(9 "F.Adhes" user "F.Adhesive")
		(11 "B.Adhes" user "B.Adhesive")
		(13 "F.Paste" user "Package Geometry/Pastemask Top")
		(15 "B.Paste" user "Package Geometry/Pastemask Bottom")
		(5 "F.SilkS" user "Ref Des/Silkscreen Top")
		(7 "B.SilkS" user "Ref Des/Silkscreen Bottom")
		(1 "F.Mask" user "Board Geometry/Soldermask Top")
		(3 "B.Mask" user "Board Geometry/Soldermask Bottom")
		(17 "Dwgs.User" user "User.Drawings")
		(19 "Cmts.User" user "User.Comments")
		(21 "Eco1.User" user "User.Eco1")
		(23 "Eco2.User" user "User.Eco2")
		(25 "Edge.Cuts" user "Board Geometry/Outline")
		(27 "Margin" user)
		(31 "F.CrtYd" user "Package Geometry/Place Bound Top")
		(29 "B.CrtYd" user "Package Geometry/Place Bound Bottom")
		(35 "F.Fab" user "Ref Des/Assembly Top")
		(33 "B.Fab" user "Ref Des/Assembly Bottom")
	)
	(footprint ""
		(layer "F.Cu")
		(at 119.508016 -256.6543 -90)
		(property "Reference" "C253"
			(at 0 0 270)
			(layer "F.SilkS")
			(hide yes)
			(effects
				(font
					(size 1.27 1.27)
				)
			)
		)
		(property "Value" ""
			(at 0 0 270)
			(layer "F.Fab")
			(effects
				(font
					(size 1.27 1.27)
				)
			)
		)
		(duplicate_pad_numbers_are_jumpers no)
		(fp_line
			(start -0.7874 0.4064)
			(end -0.7874 -0.4064)
			(stroke
				(width 0.1524)
				(type default)
			)
			(layer "F.SilkS")
		)
		(fp_line
			(start 0.7874 0.4064)
			(end -0.7874 0.4064)
			(stroke
				(width 0.1524)
				(type default)
			)
			(layer "F.SilkS")
		)
		(fp_line
			(start -0.7874 -0.4064)
			(end 0.7874 -0.4064)
			(stroke
				(width 0.1524)
				(type default)
			)
			(layer "F.SilkS")
		)
		(fp_line
			(start 0.7874 -0.4064)
			(end 0.7874 0.4064)
			(stroke
				(width 0.1524)
				(type default)
			)
			(layer "F.SilkS")
		)
		(fp_line
			(start -0.67945 0.3048)
			(end -0.67945 -0.305054)
			(stroke
				(width 0.1)
				(type default)
			)
			(layer "F.Fab")
		)
		(fp_line
			(start -0.12065 0.3048)
			(end -0.67945 0.3048)
			(stroke
				(width 0.1)
				(type default)
			)
			(layer "F.Fab")
		)
		(fp_line
			(start 0.120396 0.3048)
			(end 0.120396 0.2794)
			(stroke
				(width 0.1)
				(type default)
			)
			(layer "F.Fab")
		)
		(fp_line
			(start 0.67945 0.3048)
			(end 0.120396 0.3048)
			(stroke
				(width 0.1)
				(type default)
			)
			(layer "F.Fab")
		)
		(fp_line
			(start -0.12065 0.2794)
			(end -0.12065 0.3048)
			(stroke
				(width 0.1)
				(type default)
			)
			(layer "F.Fab")
		)
		(fp_line
			(start 0.120396 0.2794)
			(end -0.12065 0.2794)
			(stroke
				(width 0.1)
				(type default)
			)
			(layer "F.Fab")
		)
		(fp_line
			(start -0.12065 -0.2794)
			(end 0.12065 -0.2794)
			(stroke
				(width 0.1)
				(type default)
			)
			(layer "F.Fab")
		)
		(fp_line
			(start 0.12065 -0.2794)
			(end 0.12065 -0.3048)
			(stroke
				(width 0.1)
				(type default)
			)
			(layer "F.Fab")
		)
		(fp_line
			(start 0.12065 -0.3048)
			(end 0.67945 -0.3048)
			(stroke
				(width 0.1)
				(type default)
			)
			(layer "F.Fab")
		)
		(fp_line
			(start 0.67945 -0.3048)
			(end 0.67945 0.3048)
			(stroke
				(width 0.1)
				(type default)
			)
			(layer "F.Fab")
		)
		(fp_line
			(start -0.67945 -0.305054)
			(end -0.12065 -0.305054)
			(stroke
				(width 0.1)
				(type default)
			)
			(layer "F.Fab")
		)
		(fp_line
			(start -0.12065 -0.305054)
			(end -0.12065 -0.2794)
			(stroke
				(width 0.1)
				(type default)
			)
			(layer "F.Fab")
		)
		(pad "1" smd circle
			(at -0.40005 0 270)
			(size 0 0)
			(layers "F.Cu" "F.Mask" "F.Paste")
			(net "PVCCIN_CPU1")
		)
		(pad "2" smd circle
			(at 0.40005 0 270)
			(size 0 0)
			(layers "F.Cu" "F.Mask" "F.Paste")
			(net "GND")
		)
	)
	(footprint ""
		(layer "F.Cu")
		(at 162.34283 -80.159098)
		(property "Reference" "R2211"
			(at 0 0 0)
			(layer "F.SilkS")
			(hide yes)
			(effects
				(font
					(size 1.27 1.27)
				)
			)
		)
		(property "Value" ""
			(at 0 0 0)
			(layer "F.Fab")
			(effects
				(font
					(size 1.27 1.27)
				)
			)
		)
		(duplicate_pad_numbers_are_jumpers no)
		(fp_line
			(start -0.7874 -0.4064)
			(end 0.7874 -0.4064)
			(stroke
				(width 0.1524)
				(type default)
			)
			(layer "F.SilkS")
		)
		(fp_line
			(start -0.7874 0.4064)
			(end -0.7874 -0.4064)
			(stroke
				(width 0.1524)
				(type default)
			)
			(layer "F.SilkS")
		)
		(fp_line
			(start 0.7874 -0.4064)
			(end 0.7874 0.4064)
			(stroke
				(width 0.1524)
				(type default)
			)
			(layer "F.SilkS")
		)
		(fp_line
			(start 0.7874 0.4064)
			(end -0.7874 0.4064)
			(stroke
				(width 0.1524)
				(type default)
			)
			(layer "F.SilkS")
		)
		(fp_line
			(start -0.67945 -0.305054)
			(end -0.12065 -0.305054)
			(stroke
				(width 0.1)
				(type default)
			)
			(layer "F.Fab")
		)
		(fp_line
			(start -0.67945 0.3048)
			(end -0.67945 -0.305054)
			(stroke
				(width 0.1)
				(type default)
			)
			(layer "F.Fab")
		)
		(fp_line
			(start -0.12065 -0.305054)
			(end -0.12065 -0.2794)
			(stroke
				(width 0.1)
				(type default)
			)
			(layer "F.Fab")
		)
		(fp_line
			(start -0.12065 -0.2794)
			(end 0.12065 -0.2794)
			(stroke
				(width 0.1)
				(type default)
			)
			(layer "F.Fab")
		)
		(fp_line
			(start -0.12065 0.2794)
			(end -0.12065 0.3048)
			(stroke
				(width 0.1)
				(type default)
			)
			(layer "F.Fab")
		)
		(fp_line
			(start -0.12065 0.3048)
			(end -0.67945 0.3048)
			(stroke
				(width 0.1)
				(type default)
			)
			(layer "F.Fab")
		)
		(fp_line
			(start 0.120396 0.2794)
			(end -0.12065 0.2794)
			(stroke
				(width 0.1)
				(type default)
			)
			(layer "F.Fab")
		)
		(fp_line
			(start 0.120396 0.3048)
			(end 0.120396 0.2794)
			(stroke
				(width 0.1)
				(type default)
			)
			(layer "F.Fab")
		)
		(fp_line
			(start 0.12065 -0.3048)
			(end 0.67945 -0.3048)
			(stroke
				(width 0.1)
				(type default)
			)
			(layer "F.Fab")
		)
		(fp_line
			(start 0.12065 -0.2794)
			(end 0.12065 -0.3048)
			(stroke
				(width 0.1)
				(type default)
			)
			(layer "F.Fab")
		)
		(fp_line
			(start 0.67945 -0.3048)
			(end 0.67945 0.3048)
			(stroke
				(width 0.1)
				(type default)
			)
			(layer "F.Fab")
		)
		(fp_line
			(start 0.67945 0.3048)
			(end 0.120396 0.3048)
			(stroke
				(width 0.1)
				(type default)
			)
			(layer "F.Fab")
		)
		(pad "1" smd circle
			(at -0.40005 0)
			(size 0 0)
			(layers "F.Cu" "F.Mask" "F.Paste")
			(net "SMB_S3M_CPU1_3V3AUX_SCL_R")
		)
		(pad "2" smd circle
			(at 0.40005 0)
			(size 0 0)
			(layers "F.Cu" "F.Mask" "F.Paste")
			(net "SMB_S3M_CPU1_3V3AUX_SCL")
		)
	)
)
